(kicad_pcb
	(version 20260206)
	(generator "pcbnew")
	(generator_version "10.0")
	(general
		(thickness 1.6)
		(legacy_teardrops no)
	)
	(paper "A4")
	(title_block
		(title "timecard-production-celestica-r4006 — R4006-B0001-02_R01.brd")
		(comment 1 "Time Appliance Project (Time Card) / footprints 1100-1104 of 1113")
	)
	(layers
		(0 "F.Cu" signal "TOP")
		(4 "In1.Cu" signal "L02_GND1")
		(6 "In2.Cu" signal "L03_SIG1")
		(8 "In3.Cu" signal "L04_GND2")
		(10 "In4.Cu" signal "L05_VCC1")
		(12 "In5.Cu" signal "L06_VCC2")
		(14 "In6.Cu" signal "L07_GND3")
		(16 "In7.Cu" signal "L08_SIG2")
		(18 "In8.Cu" signal "L09_GND4")
		(2 "B.Cu" signal "BOTTOM")
		(9 "F.Adhes" user "F.Adhesive")
		(11 "B.Adhes" user "B.Adhesive")
		(13 "F.Paste" user "Package Geometry/Pastemask Top")
		(15 "B.Paste" user "Package Geometry/Pastemask Bottom")
		(5 "F.SilkS" user "Ref Des/Silkscreen Top")
		(7 "B.SilkS" user "Ref Des/Silkscreen Bottom")
		(1 "F.Mask" user "Board Geometry/Soldermask Top")
		(3 "B.Mask" user "Board Geometry/Soldermask Bottom")
		(17 "Dwgs.User" user "User.Drawings")
		(19 "Cmts.User" user "User.Comments")
		(21 "Eco1.User" user "User.Eco1")
		(23 "Eco2.User" user "User.Eco2")
		(25 "Edge.Cuts" user "Board Geometry/Outline")
		(27 "Margin" user)
		(31 "F.CrtYd" user "Package Geometry/Place Bound Top")
		(29 "B.CrtYd" user "Package Geometry/Place Bound Bottom")
		(35 "F.Fab" user "Ref Des/Assembly Top")
		(33 "B.Fab" user "Ref Des/Assembly Bottom")
	)
	(footprint ""
		(layer "B.Cu")
		(at 54.737 -16.129 -90)
		(property "Reference" "C289"
			(at -4.064 -0.72263 270)
			(unlocked yes)
			(layer "B.SilkS")
			(effects
				(font
					(size 0.7874 0.5842)
					(thickness 0.1524)
				)
				(justify mirror)
			)
		)
		(property "Value" "VAL*"
			(at -0.0762 2.067306 270)
			(unlocked yes)
			(layer "B.Fab")
			(hide yes)
			(effects
				(font
					(size 0.7874 0.5842)
					(thickness 0.1524)
				)
				(justify mirror)
			)
		)
		(property "Device Type" "CAPACITOR-G105-0C106-BM,10UF,2A"
			(at -0.0508 1.127506 270)
			(unlocked yes)
			(layer "B.Fab")
			(hide yes)
			(effects
				(font
					(size 0.7874 0.5842)
					(thickness 0.1524)
				)
				(justify mirror)
			)
		)
		(property "User Part Number" "PARTNUM*"
			(at -0.1016 4.023106 270)
			(unlocked yes)
			(layer "Cmts.User")
			(hide yes)
			(effects
				(font
					(size 0.7874 0.5842)
					(thickness 0.1524)
				)
				(justify mirror)
			)
		)
		(property "Tolerance" "TOL*"
			(at -0.0762 3.032506 270)
			(unlocked yes)
			(layer "Cmts.User")
			(hide yes)
			(effects
				(font
					(size 0.7874 0.5842)
					(thickness 0.1524)
				)
				(justify mirror)
			)
		)
		(duplicate_pad_numbers_are_jumpers no)
		(fp_line
			(start -1.143 0.5588)
			(end -1.143 -0.5588)
			(stroke
				(width 0.1)
				(type default)
			)
			(layer "B.SilkS")
		)
		(fp_line
			(start 1.143 0.5588)
			(end -1.143 0.5588)
			(stroke
				(width 0.1)
				(type default)
			)
			(layer "B.SilkS")
		)
		(fp_line
			(start -1.143 -0.5588)
			(end 1.143 -0.5588)
			(stroke
				(width 0.1)
				(type default)
			)
			(layer "B.SilkS")
		)
		(fp_line
			(start 1.143 -0.5588)
			(end 1.143 0.5588)
			(stroke
				(width 0.1)
				(type default)
			)
			(layer "B.SilkS")
		)
		(fp_poly
			(pts
				(xy 1.143 0.5588) (xy -1.143 0.5588) (xy -1.143 -0.5588) (xy 1.143 -0.5588)
			)
			(stroke
				(width 0)
				(type default)
			)
			(fill no)
			(layer "B.CrtYd")
		)
		(fp_line
			(start -0.508 0.3048)
			(end -0.508 -0.3048)
			(stroke
				(width 0.1)
				(type default)
			)
			(layer "B.Fab")
		)
		(fp_line
			(start 0.508 0.3048)
			(end -0.508 0.3048)
			(stroke
				(width 0.1)
				(type default)
			)
			(layer "B.Fab")
		)
		(fp_line
			(start -0.508 -0.3048)
			(end 0.508 -0.3048)
			(stroke
				(width 0.1)
				(type default)
			)
			(layer "B.Fab")
		)
		(fp_line
			(start 0.508 -0.3048)
			(end 0.508 0.3048)
			(stroke
				(width 0.1)
				(type default)
			)
			(layer "B.Fab")
		)
		(pad "1" smd rect
			(at 0.5334 0 90)
			(size 0.7112 0.6096)
			(layers "B.Cu" "B.Mask" "B.Paste")
			(net "XP3R3V_PCIE")
		)
		(pad "2" smd rect
			(at -0.5334 0 90)
			(size 0.7112 0.6096)
			(layers "B.Cu" "B.Mask" "B.Paste")
			(net "SG")
		)
		(zone
			(layer "B.Cu")
			(hatch none 0.5)
			(connect_pads
				(clearance 0)
			)
			(min_thickness 0.25)
			(keepout
				(tracks not_allowed)
				(vias allowed)
				(pads allowed)
				(copperpour not_allowed)
				(footprints allowed)
			)
			(placement
				(enabled no)
				(sheetname "")
			)
			(fill
				(thermal_gap 0.5)
				(thermal_bridge_width 0.5)
				(island_removal_mode 0)
			)
			(polygon
				(pts
					(xy 54.4322 -16.0528) (xy 55.0418 -16.0528) (xy 55.0418 -16.2052) (xy 54.4322 -16.2052)
				)
			)
		)
		(zone
			(layer "B.Cu")
			(hatch none 0.5)
			(connect_pads
				(clearance 0)
			)
			(min_thickness 0.25)
			(keepout
				(tracks allowed)
				(vias not_allowed)
				(pads allowed)
				(copperpour not_allowed)
				(footprints allowed)
			)
			(placement
				(enabled no)
				(sheetname "")
			)
			(fill
				(thermal_gap 0.5)
				(thermal_bridge_width 0.5)
				(island_removal_mode 0)
			)
			(polygon
				(pts
					(xy 54.4322 -16.0528) (xy 55.0418 -16.0528) (xy 55.0418 -16.2052) (xy 54.4322 -16.2052)
				)
			)
		)
	)
	(footprint ""
		(layer "B.Cu")
		(at 102.5398 -64.2874 90)
		(property "Reference" "R293"
			(at 3.5306 -0.09017 270)
			(unlocked yes)
			(layer "B.SilkS")
			(effects
				(font
					(size 0.7874 0.5842)
					(thickness 0.1524)
				)
				(justify mirror)
			)
		)
		(property "Value" "VAL*"
			(at -0.02032 2.13233 90)
			(unlocked yes)
			(layer "B.Fab")
			(hide yes)
			(effects
				(font
					(size 0.7874 0.5842)
					(thickness 0.1524)
				)
				(justify mirror)
			)
		)
		(property "Tolerance" "TOL*"
			(at -0.044704 3.05435 90)
			(unlocked yes)
			(layer "Cmts.User")
			(hide yes)
			(effects
				(font
					(size 0.7874 0.5842)
					(thickness 0.1524)
				)
				(justify mirror)
			)
		)
		(property "User Part Number" "PARTNUM*"
			(at -0.02032 4.024884 90)
			(unlocked yes)
			(layer "Cmts.User")
			(hide yes)
			(effects
				(font
					(size 0.7874 0.5842)
					(thickness 0.1524)
				)
				(justify mirror)
			)
		)
		(property "Device Type" "RESISTOR-G155-14701-01,4.7KOHMA"
			(at -0.008382 1.210564 90)
			(unlocked yes)
			(layer "B.Fab")
			(hide yes)
			(effects
				(font
					(size 0.7874 0.5842)
					(thickness 0.1524)
				)
				(justify mirror)
			)
		)
		(duplicate_pad_numbers_are_jumpers no)
		(fp_line
			(start 1.143 -0.5588)
			(end 1.143 0.5588)
			(stroke
				(width 0.1)
				(type default)
			)
			(layer "B.SilkS")
		)
		(fp_line
			(start -1.143 -0.5588)
			(end 1.143 -0.5588)
			(stroke
				(width 0.1)
				(type default)
			)
			(layer "B.SilkS")
		)
		(fp_line
			(start 1.143 0.5588)
			(end -1.143 0.5588)
			(stroke
				(width 0.1)
				(type default)
			)
			(layer "B.SilkS")
		)
		(fp_line
			(start -1.143 0.5588)
			(end -1.143 -0.5588)
			(stroke
				(width 0.1)
				(type default)
			)
			(layer "B.SilkS")
		)
		(fp_rect
			(start -1.143 0.5588)
			(end 1.143 -0.5588)
			(stroke
				(width 0)
				(type default)
			)
			(fill no)
			(layer "B.CrtYd")
		)
		(fp_line
			(start 0.508 -0.3048)
			(end 0.508 0.3048)
			(stroke
				(width 0.1)
				(type default)
			)
			(layer "B.Fab")
		)
		(fp_line
			(start -0.508 -0.3048)
			(end 0.508 -0.3048)
			(stroke
				(width 0.1)
				(type default)
			)
			(layer "B.Fab")
		)
		(fp_line
			(start 0.508 0.3048)
			(end -0.508 0.3048)
			(stroke
				(width 0.1)
				(type default)
			)
			(layer "B.Fab")
		)
		(fp_line
			(start -0.508 0.3048)
			(end -0.508 -0.3048)
			(stroke
				(width 0.1)
				(type default)
			)
			(layer "B.Fab")
		)
		(pad "1" smd rect
			(at 0.5334 0 270)
			(size 0.7112 0.6096)
			(layers "B.Cu" "B.Mask" "B.Paste")
			(net "SG")
		)
		(pad "2" smd rect
			(at -0.5334 0 270)
			(size 0.7112 0.6096)
			(layers "B.Cu" "B.Mask" "B.Paste")
			(net "FPGA_IO_4")
		)
		(zone
			(layer "B.Cu")
			(hatch none 0.5)
			(connect_pads
				(clearance 0)
			)
			(min_thickness 0.25)
			(keepout
				(tracks allowed)
				(vias not_allowed)
				(pads allowed)
				(copperpour not_allowed)
				(footprints allowed)
			)
			(placement
				(enabled no)
				(sheetname "")
			)
			(fill
				(thermal_gap 0.5)
				(thermal_bridge_width 0.5)
				(island_removal_mode 0)
			)
			(polygon
				(pts
					(xy 102.8446 -64.2112) (xy 102.8446 -64.3636) (xy 102.235 -64.3636) (xy 102.235 -64.2112)
				)
			)
		)
	)
	(footprint ""
		(layer "B.Cu")
		(at 126.619 -89.535 -90)
		(property "Reference" "R109"
			(at -2.794 0.03937 270)
			(unlocked yes)
			(layer "B.SilkS")
			(effects
				(font
					(size 0.7874 0.5842)
					(thickness 0.1524)
				)
				(justify mirror)
			)
		)
		(property "Value" "VAL*"
			(at -0.02032 2.13233 270)
			(unlocked yes)
			(layer "B.Fab")
			(hide yes)
			(effects
				(font
					(size 0.7874 0.5842)
					(thickness 0.1524)
				)
				(justify mirror)
			)
		)
		(property "Tolerance" "TOL*"
			(at -0.044704 3.05435 270)
			(unlocked yes)
			(layer "Cmts.User")
			(hide yes)
			(effects
				(font
					(size 0.7874 0.5842)
					(thickness 0.1524)
				)
				(justify mirror)
			)
		)
		(property "User Part Number" "PARTNUM*"
			(at -0.02032 4.024884 270)
			(unlocked yes)
			(layer "Cmts.User")
			(hide yes)
			(effects
				(font
					(size 0.7874 0.5842)
					(thickness 0.1524)
				)
				(justify mirror)
			)
		)
		(property "Device Type" "RESISTOR-G155-133R0-01,33OHM,1%"
			(at -0.008382 1.210564 270)
			(unlocked yes)
			(layer "B.Fab")
			(hide yes)
			(effects
				(font
					(size 0.7874 0.5842)
					(thickness 0.1524)
				)
				(justify mirror)
			)
		)
		(duplicate_pad_numbers_are_jumpers no)
		(fp_line
			(start -1.143 0.5588)
			(end -1.143 -0.5588)
			(stroke
				(width 0.1)
				(type default)
			)
			(layer "B.SilkS")
		)
		(fp_line
			(start 1.143 0.5588)
			(end -1.143 0.5588)
			(stroke
				(width 0.1)
				(type default)
			)
			(layer "B.SilkS")
		)
		(fp_line
			(start -1.143 -0.5588)
			(end 1.143 -0.5588)
			(stroke
				(width 0.1)
				(type default)
			)
			(layer "B.SilkS")
		)
		(fp_line
			(start 1.143 -0.5588)
			(end 1.143 0.5588)
			(stroke
				(width 0.1)
				(type default)
			)
			(layer "B.SilkS")
		)
		(fp_rect
			(start 1.143 0.5588)
			(end -1.143 -0.5588)
			(stroke
				(width 0)
				(type default)
			)
			(fill no)
			(layer "B.CrtYd")
		)
		(fp_line
			(start -0.508 0.3048)
			(end -0.508 -0.3048)
			(stroke
				(width 0.1)
				(type default)
			)
			(layer "B.Fab")
		)
		(fp_line
			(start 0.508 0.3048)
			(end -0.508 0.3048)
			(stroke
				(width 0.1)
				(type default)
			)
			(layer "B.Fab")
		)
		(fp_line
			(start -0.508 -0.3048)
			(end 0.508 -0.3048)
			(stroke
				(width 0.1)
				(type default)
			)
			(layer "B.Fab")
		)
		(fp_line
			(start 0.508 -0.3048)
			(end 0.508 0.3048)
			(stroke
				(width 0.1)
				(type default)
			)
			(layer "B.Fab")
		)
		(pad "1" smd rect
			(at 0.5334 0 90)
			(size 0.7112 0.6096)
			(layers "B.Cu" "B.Mask" "B.Paste")
			(net "UART_GPS_TX_FPGA_RX")
		)
		(pad "2" smd rect
			(at -0.5334 0 90)
			(size 0.7112 0.6096)
			(layers "B.Cu" "B.Mask" "B.Paste")
			(net "GPS_UART_TXD")
		)
		(zone
			(layer "B.Cu")
			(hatch none 0.5)
			(connect_pads
				(clearance 0)
			)
			(min_thickness 0.25)
			(keepout
				(tracks allowed)
				(vias not_allowed)
				(pads allowed)
				(copperpour not_allowed)
				(footprints allowed)
			)
			(placement
				(enabled no)
				(sheetname "")
			)
			(fill
				(thermal_gap 0.5)
				(thermal_bridge_width 0.5)
				(island_removal_mode 0)
			)
			(polygon
				(pts
					(xy 126.3142 -89.4588) (xy 126.9238 -89.4588) (xy 126.9238 -89.6112) (xy 126.3142 -89.6112)
				)
			)
		)
	)
	(footprint ""
		(layer "B.Cu")
		(at 119.761 -24.511 180)
		(property "Reference" "R482"
			(at 0 1.23063 0)
			(unlocked yes)
			(layer "B.SilkS")
			(effects
				(font
					(size 0.7874 0.5842)
					(thickness 0.1524)
				)
				(justify mirror)
			)
		)
		(property "Value" "VAL*"
			(at -0.02032 2.13233 180)
			(unlocked yes)
			(layer "B.Fab")
			(hide yes)
			(effects
				(font
					(size 0.7874 0.5842)
					(thickness 0.1524)
				)
				(justify mirror)
			)
		)
		(property "Tolerance" "TOL*"
			(at -0.044704 3.05435 180)
			(unlocked yes)
			(layer "Cmts.User")
			(hide yes)
			(effects
				(font
					(size 0.7874 0.5842)
					(thickness 0.1524)
				)
				(justify mirror)
			)
		)
		(property "User Part Number" "PARTNUM*"
			(at -0.02032 4.024884 180)
			(unlocked yes)
			(layer "Cmts.User")
			(hide yes)
			(effects
				(font
					(size 0.7874 0.5842)
					(thickness 0.1524)
				)
				(justify mirror)
			)
		)
		(property "Device Type" "RESISTOR-G155-14701-01,4.7KOHMA"
			(at -0.008382 1.210564 180)
			(unlocked yes)
			(layer "B.Fab")
			(hide yes)
			(effects
				(font
					(size 0.7874 0.5842)
					(thickness 0.1524)
				)
				(justify mirror)
			)
		)
		(duplicate_pad_numbers_are_jumpers no)
		(fp_line
			(start 1.143 0.5588)
			(end -1.143 0.5588)
			(stroke
				(width 0.1)
				(type default)
			)
			(layer "B.SilkS")
		)
		(fp_line
			(start 1.143 -0.5588)
			(end 1.143 0.5588)
			(stroke
				(width 0.1)
				(type default)
			)
			(layer "B.SilkS")
		)
		(fp_line
			(start -1.143 0.5588)
			(end -1.143 -0.5588)
			(stroke
				(width 0.1)
				(type default)
			)
			(layer "B.SilkS")
		)
		(fp_line
			(start -1.143 -0.5588)
			(end 1.143 -0.5588)
			(stroke
				(width 0.1)
				(type default)
			)
			(layer "B.SilkS")
		)
		(fp_poly
			(pts
				(xy 1.143 0.5588) (xy -1.143 0.5588) (xy -1.143 -0.5588) (xy 1.143 -0.5588)
			)
			(stroke
				(width 0)
				(type default)
			)
			(fill no)
			(layer "B.CrtYd")
		)
		(fp_line
			(start 0.508 0.3048)
			(end -0.508 0.3048)
			(stroke
				(width 0.1)
				(type default)
			)
			(layer "B.Fab")
		)
		(fp_line
			(start 0.508 -0.3048)
			(end 0.508 0.3048)
			(stroke
				(width 0.1)
				(type default)
			)
			(layer "B.Fab")
		)
		(fp_line
			(start -0.508 0.3048)
			(end -0.508 -0.3048)
			(stroke
				(width 0.1)
				(type default)
			)
			(layer "B.Fab")
		)
		(fp_line
			(start -0.508 -0.3048)
			(end 0.508 -0.3048)
			(stroke
				(width 0.1)
				(type default)
			)
			(layer "B.Fab")
		)
		(pad "1" smd rect
			(at 0.5334 0)
			(size 0.7112 0.6096)
			(layers "B.Cu" "B.Mask" "B.Paste")
			(net "XP3R3V_FPGA")
		)
		(pad "2" smd rect
			(at -0.5334 0)
			(size 0.7112 0.6096)
			(layers "B.Cu" "B.Mask" "B.Paste")
			(net "MUX3_SEL")
		)
		(zone
			(layer "B.Cu")
			(hatch none 0.5)
			(connect_pads
				(clearance 0)
			)
			(min_thickness 0.25)
			(keepout
				(tracks allowed)
				(vias not_allowed)
				(pads allowed)
				(copperpour not_allowed)
				(footprints allowed)
			)
			(placement
				(enabled no)
				(sheetname "")
			)
			(fill
				(thermal_gap 0.5)
				(thermal_bridge_width 0.5)
				(island_removal_mode 0)
			)
			(polygon
				(pts
					(xy 119.6848 -24.8158) (xy 119.6848 -24.2062) (xy 119.8372 -24.2062) (xy 119.8372 -24.8158)
				)
			)
		)
		(zone
			(layer "B.Cu")
			(hatch none 0.5)
			(connect_pads
				(clearance 0)
			)
			(min_thickness 0.25)
			(keepout
				(tracks not_allowed)
				(vias allowed)
				(pads allowed)
				(copperpour not_allowed)
				(footprints allowed)
			)
			(placement
				(enabled no)
				(sheetname "")
			)
			(fill
				(thermal_gap 0.5)
				(thermal_bridge_width 0.5)
				(island_removal_mode 0)
			)
			(polygon
				(pts
					(xy 119.6848 -24.8158) (xy 119.6848 -24.2062) (xy 119.8372 -24.2062) (xy 119.8372 -24.8158)
				)
			)
		)
	)
	(footprint ""
		(layer "B.Cu")
		(at 53.975 -88.9)
		(property "Reference" "R447"
			(at 0.127 -4.40563 0)
			(unlocked yes)
			(layer "B.SilkS")
			(effects
				(font
					(size 0.7874 0.5842)
					(thickness 0.1524)
				)
				(justify mirror)
			)
		)
		(property "Value" "VAL*"
			(at -0.02032 2.13233 0)
			(unlocked yes)
			(layer "B.Fab")
			(hide yes)
			(effects
				(font
					(size 0.7874 0.5842)
					(thickness 0.1524)
				)
				(justify mirror)
			)
		)
		(property "Tolerance" "TOL*"
			(at -0.044704 3.05435 0)
			(unlocked yes)
			(layer "Cmts.User")
			(hide yes)
			(effects
				(font
					(size 0.7874 0.5842)
					(thickness 0.1524)
				)
				(justify mirror)
			)
		)
		(property "User Part Number" "PARTNUM*"
			(at -0.02032 4.024884 0)
			(unlocked yes)
			(layer "Cmts.User")
			(hide yes)
			(effects
				(font
					(size 0.7874 0.5842)
					(thickness 0.1524)
				)
				(justify mirror)
			)
		)
		(property "Device Type" "RESISTOR-G155-11002-01,10KOHM,A"
			(at -0.008382 1.210564 0)
			(unlocked yes)
			(layer "B.Fab")
			(hide yes)
			(effects
				(font
					(size 0.7874 0.5842)
					(thickness 0.1524)
				)
				(justify mirror)
			)
		)
		(duplicate_pad_numbers_are_jumpers no)
		(fp_line
			(start -1.143 -0.5588)
			(end 1.143 -0.5588)
			(stroke
				(width 0.1)
				(type default)
			)
			(layer "B.SilkS")
		)
		(fp_line
			(start -1.143 0.5588)
			(end -1.143 -0.5588)
			(stroke
				(width 0.1)
				(type default)
			)
			(layer "B.SilkS")
		)
		(fp_line
			(start 1.143 -0.5588)
			(end 1.143 0.5588)
			(stroke
				(width 0.1)
				(type default)
			)
			(layer "B.SilkS")
		)
		(fp_line
			(start 1.143 0.5588)
			(end -1.143 0.5588)
			(stroke
				(width 0.1)
				(type default)
			)
			(layer "B.SilkS")
		)
		(fp_poly
			(pts
				(xy 1.143 0.5588) (xy -1.143 0.5588) (xy -1.143 -0.5588) (xy 1.143 -0.5588)
			)
			(stroke
				(width 0)
				(type default)
			)
			(fill no)
			(layer "B.CrtYd")
		)
		(fp_line
			(start -0.508 -0.3048)
			(end 0.508 -0.3048)
			(stroke
				(width 0.1)
				(type default)
			)
			(layer "B.Fab")
		)
		(fp_line
			(start -0.508 0.3048)
			(end -0.508 -0.3048)
			(stroke
				(width 0.1)
				(type default)
			)
			(layer "B.Fab")
		)
		(fp_line
			(start 0.508 -0.3048)
			(end 0.508 0.3048)
			(stroke
				(width 0.1)
				(type default)
			)
			(layer "B.Fab")
		)
		(fp_line
			(start 0.508 0.3048)
			(end -0.508 0.3048)
			(stroke
				(width 0.1)
				(type default)
			)
			(layer "B.Fab")
		)
		(pad "1" smd rect
			(at 0.5334 0 180)
			(size 0.7112 0.6096)
			(layers "B.Cu" "B.Mask" "B.Paste")
			(net "XP3R3V_FT4232")
		)
		(pad "2" smd rect
			(at -0.5334 0 180)
			(size 0.7112 0.6096)
			(layers "B.Cu" "B.Mask" "B.Paste")
			(net "FTDI_EE_CLK")
		)
		(zone
			(layer "B.Cu")
			(hatch none 0.5)
			(connect_pads
				(clearance 0)
			)
			(min_thickness 0.25)
			(keepout
				(tracks allowed)
				(vias not_allowed)
				(pads allowed)
				(copperpour not_allowed)
				(footprints allowed)
			)
			(placement
				(enabled no)
				(sheetname "")
			)
			(fill
				(thermal_gap 0.5)
				(thermal_bridge_width 0.5)
				(island_removal_mode 0)
			)
			(polygon
				(pts
					(xy 54.0512 -88.5952) (xy 54.0512 -89.2048) (xy 53.8988 -89.2048) (xy 53.8988 -88.5952)
				)
			)
		)
		(zone
			(layer "B.Cu")
			(hatch none 0.5)
			(connect_pads
				(clearance 0)
			)
			(min_thickness 0.25)
			(keepout
				(tracks not_allowed)
				(vias allowed)
				(pads allowed)
				(copperpour not_allowed)
				(footprints allowed)
			)
			(placement
				(enabled no)
				(sheetname "")
			)
			(fill
				(thermal_gap 0.5)
				(thermal_bridge_width 0.5)
				(island_removal_mode 0)
			)
			(polygon
				(pts
					(xy 54.0512 -88.5952) (xy 54.0512 -89.2048) (xy 53.8988 -89.2048) (xy 53.8988 -88.5952)
				)
			)
		)
	)
)
